# BASEBOARD_FAB2 (Tioga Pass) — schematic netlist excerpt (pin names and nets, part order shuffled) for the footprints in the layout excerpt that follows; sources: Cadence DE-HDL packaged netlist, KiCad conversion of Wiwynn_Tioga_Pass_MB.brd

J6U2  SCONN288_H44441003  SCONN  pkg PIP  page 48
  \12v\(1)  = P12V_NVDIMM_ABC
  VSS(93)  = GND
  DQ(4)  = M_C_DQ<4>
  VSS(92)  = GND
  DQ(0)  = M_C_DQ<0>
  VSS(91)  = GND
  DQS9P  = M_C_DQS_DP<9>
  DQS9N  = M_C_DQS_DN<9>
  VSS(90)  = GND
  DQ(6)  = M_C_DQ<6>
  VSS(89)  = GND
  DQ(2)  = M_C_DQ<2>
  VSS(88)  = GND
  DQ(12)  = M_C_DQ<12>
  VSS(87)  = GND
  DQ(8)  = M_C_DQ<8>
  VSS(86)  = GND
  DQS10P  = M_C_DQS_DP<10>
  DQS10N  = M_C_DQS_DN<10>
  VSS(85)  = GND
  DQ(14)  = M_C_DQ<14>
  VSS(84)  = GND
  DQ(10)  = M_C_DQ<10>
  VSS(83)  = GND
  DQ(20)  = M_C_DQ<20>
  VSS(82)  = GND
  DQ(16)  = M_C_DQ<16>
  VSS(81)  = GND
  DQS11P  = M_C_DQS_DP<11>
  DQS11N  = M_C_DQS_DN<11>
  VSS(80)  = GND
  DQ(22)  = M_C_DQ<22>
  VSS(79)  = GND
  DQ(18)  = M_C_DQ<18>
  VSS(78)  = GND
  DQ(28)  = M_C_DQ<28>
  VSS(77)  = GND
  DQ(24)  = M_C_DQ<24>
  VSS(76)  = GND
  DQS12P  = M_C_DQS_DP<12>
  DQS12N  = M_C_DQS_DN<12>
  VSS(75)  = GND
  DQ(30)  = M_C_DQ<30>
  VSS(74)  = GND
  DQ(26)  = M_C_DQ<26>
  VSS(73)  = GND
  CB(4)  = M_C_ECC<4>
  VSS(72)  = GND
  CB(0)  = M_C_ECC<0>
  VSS(71)  = GND
  DQS17P  = M_C_DQS_DP<17>
  DQS17N  = M_C_DQS_DN<17>
  VSS(70)  = GND
  CB(6)  = M_C_ECC<6>
  VSS(69)  = GND
  CB(2)  = M_C_ECC<2>
  VSS(68)  = GND
  RESET_N  = M_ABC_RST_N
  VDD(25)  = PVDDQ_ABC
  CKE(0)  = M_C_CKE<2>
  VDD(24)  = PVDDQ_ABC
  ACT_N  = M_C_ACT_N
  BG(0)  = M_C_BG<0>
  VDD(23)  = PVDDQ_ABC
  A12  = M_C_MA<12>
  A9  = M_C_MA<9>
  VDD(22)  = PVDDQ_ABC
  A8  = M_C_MA<8>
  A6  = M_C_MA<6>
  VDD(21)  = PVDDQ_ABC
  A3  = M_C_MA<3>
  A1  = M_C_MA<1>
  VDD(20)  = PVDDQ_ABC
  CK0P  = M_C_CLK_DP<2>
  CK0N  = M_C_CLK_DN<2>
  VDD(19)  = PVDDQ_ABC
  VTT(1)  = PVTT_ABC
  EVENT_N  = FM_DIMM_EVENT_COD_N
  A0  = M_C_MA<0>
  VDD(18)  = PVDDQ_ABC
  BA(0)  = M_C_BA<0>
  A16_RAS_N  = M_C_MA<16>
  VDD(17)  = PVDDQ_ABC
  S0_N  = M_C_CS_N<4>
  VDD(16)  = PVDDQ_ABC
  A15_CAS_N  = M_C_MA<15>
  ODT(0)  = M_C_ODT<2>
  VDD(15)  = PVDDQ_ABC
  S1_N  = M_C_CS_N<5>
  VDD(14)  = PVDDQ_ABC
  ODT(1)  = M_C_ODT<3>
  VDD(13)  = PVDDQ_ABC
  S2_N_C(0)  = M_C_CS_N<6>
  VSS(67)  = GND
  DQ(36)  = M_C_DQ<36>
  VSS(66)  = GND
  DQ(32)  = M_C_DQ<32>
  VSS(65)  = GND
  DQS13P  = M_C_DQS_DP<13>
  DQS13N  = M_C_DQS_DN<13>
  VSS(64)  = GND
  DQ(38)  = M_C_DQ<38>
  VSS(63)  = GND
  DQ(34)  = M_C_DQ<34>
  VSS(62)  = GND
  DQ(44)  = M_C_DQ<44>
  VSS(61)  = GND
  DQ(40)  = M_C_DQ<40>
  VSS(60)  = GND
  DQS14P  = M_C_DQS_DP<14>
  DQS14N  = M_C_DQS_DN<14>
  VSS(59)  = GND
  DQ(46)  = M_C_DQ<46>
  VSS(58)  = GND
  DQ(42)  = M_C_DQ<42>
  VSS(57)  = GND
  DQ(52)  = M_C_DQ<52>
  VSS(56)  = GND
  DQ(48)  = M_C_DQ<48>
  VSS(55)  = GND
  DQS15P  = M_C_DQS_DP<15>
  DQS15N  = M_C_DQS_DN<15>
  VSS(54)  = GND
  DQ(54)  = M_C_DQ<54>
  VSS(53)  = GND
  DQ(50)  = M_C_DQ<50>
  VSS(52)  = GND
  DQ(60)  = M_C_DQ<60>
  VSS(51)  = GND
  DQ(56)  = M_C_DQ<56>
  VSS(50)  = GND
  DQS16P  = M_C_DQS_DP<16>
  DQS16N  = M_C_DQS_DN<16>
  VSS(49)  = GND
  DQ(62)  = M_C_DQ<62>
  VSS(48)  = GND
  DQ(58)  = M_C_DQ<58>
  VSS(47)  = GND
  SA(0)  = PVPP_ABC
  SA(1)  = GND
  SCL  = SMB_DDR_ABC_VPP_SCL
  VPP(4)  = PVPP_ABC
  VPP(3)  = PVPP_ABC
  RFU(2)  = TP_CH_C_DIMM_C1_RFU_2
  \12v\(0)  = P12V_NVDIMM_ABC
  VREFCA  = M_C_VREF
  VSS(46)  = GND
  DQ(5)  = M_C_DQ<5>
  VSS(45)  = GND
  DQ(1)  = M_C_DQ<1>
  VSS(44)  = GND
  DQS0N  = M_C_DQS_DN<0>
  DQS0P  = M_C_DQS_DP<0>
  VSS(43)  = GND
  DQ(7)  = M_C_DQ<7>
  VSS(42)  = GND
  DQ(3)  = M_C_DQ<3>
  VSS(41)  = GND
  DQ(13)  = M_C_DQ<13>
  VSS(40)  = GND
  DQ(9)  = M_C_DQ<9>
  VSS(39)  = GND
  DQS1N  = M_C_DQS_DN<1>
  DQS1P  = M_C_DQS_DP<1>
  VSS(38)  = GND
  DQ(15)  = M_C_DQ<15>
  VSS(37)  = GND
  DQ(11)  = M_C_DQ<11>
  VSS(36)  = GND
  DQ(21)  = M_C_DQ<21>
  VSS(35)  = GND
  DQ(17)  = M_C_DQ<17>
  VSS(34)  = GND
  DQS2N  = M_C_DQS_DN<2>
  DQS2P  = M_C_DQS_DP<2>
  VSS(33)  = GND
  DQ(23)  = M_C_DQ<23>
  VSS(32)  = GND
  DQ(19)  = M_C_DQ<19>
  VSS(31)  = GND
  DQ(29)  = M_C_DQ<29>
  VSS(30)  = GND
  DQ(25)  = M_C_DQ<25>
  VSS(29)  = GND
  DQS3N  = M_C_DQS_DN<3>
  DQS3P  = M_C_DQS_DP<3>
  VSS(28)  = GND
  DQ(31)  = M_C_DQ<31>
  VSS(27)  = GND
  DQ(27)  = M_C_DQ<27>
  VSS(26)  = GND
  CB(5)  = M_C_ECC<5>
  VSS(25)  = GND
  CB(1)  = M_C_ECC<1>
  VSS(24)  = GND
  DQS8N  = M_C_DQS_DN<8>
  DQS8P  = M_C_DQS_DP<8>
  VSS(23)  = GND
  CB(7)  = M_C_ECC<7>
  VSS(22)  = GND
  CB(3)  = M_C_ECC<3>
  VSS(21)  = GND
  CKE(1)  = M_C_CKE<3>
  VDD(12)  = PVDDQ_ABC
  RFU(0)  = TP_CH_C_DIMM_C1_RFU_0
  VDD(11)  = PVDDQ_ABC
  BG(1)  = M_C_BG<1>
  ALERT_N  = M_C_ALERT_N
  VDD(10)  = PVDDQ_ABC
  A11  = M_C_MA<11>
  A7  = M_C_MA<7>
  VDD(9)  = PVDDQ_ABC
  A5  = M_C_MA<5>
  A4  = M_C_MA<4>
  VDD(8)  = PVDDQ_ABC
  A2  = M_C_MA<2>
  VDD(7)  = PVDDQ_ABC
  CK1P  = M_C_CLK_DP<3>
  CK1N  = M_C_CLK_DN<3>
  VDD(6)  = PVDDQ_ABC
  VTT(0)  = PVTT_ABC
  PAR  = M_C_PAR
  VDD(5)  = PVDDQ_ABC
  BA(1)  = M_C_BA<1>
  A10  = M_C_MA<10>
  VDD(4)  = PVDDQ_ABC
  RFU(1)  = TP_CH_C_DIMM_C1_RFU_1
  A14_WE_N  = M_C_MA<14>
  VDD(3)  = PVDDQ_ABC
  SAVE_N_NC  = FM_ADR_COMPLETE_ABC_N
  VDD(2)  = PVDDQ_ABC
  A13  = M_C_MA<13>
  VDD(1)  = PVDDQ_ABC
  A17  = M_C_MA<17>
  C(2)  = M_C_C<2>
  VDD(0)  = PVDDQ_ABC
  S3_N_C(1)  = M_C_CS_N<7>
  SA(2)  = PVPP_ABC
  VSS(20)  = GND
  DQ(37)  = M_C_DQ<37>
  VSS(19)  = GND
  DQ(33)  = M_C_DQ<33>
  VSS(18)  = GND
  DQS4N  = M_C_DQS_DN<4>
  DQS4P  = M_C_DQS_DP<4>
  VSS(17)  = GND
  DQ(39)  = M_C_DQ<39>
  VSS(16)  = GND
  DQ(35)  = M_C_DQ<35>
  VSS(15)  = GND
  DQ(45)  = M_C_DQ<45>
  VSS(14)  = GND
  DQ(41)  = M_C_DQ<41>
  VSS(13)  = GND
  DQS5N  = M_C_DQS_DN<5>
  DQS5P  = M_C_DQS_DP<5>
  VSS(12)  = GND
  DQ(47)  = M_C_DQ<47>
  VSS(11)  = GND
  DQ(43)  = M_C_DQ<43>
  VSS(10)  = GND
  DQ(53)  = M_C_DQ<53>
  VSS(9)  = GND
  DQ(49)  = M_C_DQ<49>
  VSS(8)  = GND
  DQS6N  = M_C_DQS_DN<6>
  DQS6P  = M_C_DQS_DP<6>
  VSS(7)  = GND
  DQ(55)  = M_C_DQ<55>
  VSS(6)  = GND
  DQ(51)  = M_C_DQ<51>
  VSS(5)  = GND
  DQ(61)  = M_C_DQ<61>
  VSS(4)  = GND
  DQ(57)  = M_C_DQ<57>
  VSS(3)  = GND
  DQS7N  = M_C_DQS_DN<7>
  DQS7P  = M_C_DQS_DP<7>
  VSS(2)  = GND
  DQ(63)  = M_C_DQ<63>
  VSS(1)  = GND
  DQ(59)  = M_C_DQ<59>
  VSS(0)  = GND
  VDDSPD  = PVPP_ABC
  SDA  = SMB_DDR_ABC_VPP_SDA
  VPP(1)  = PVPP_ABC
  VPP(0)  = PVPP_ABC
  VPP(2)  = PVPP_ABC

(kicad_pcb
	(version 20260206)
	(generator "pcbnew")
	(generator_version "10.0")
	(general
		(thickness 1.6)
		(legacy_teardrops no)
	)
	(paper "A4")
	(title_block
		(title "Wiwynn_Tioga_Pass_MB.brd")
		(comment 1 "Tioga Pass / footprint 2838 of 4770 (J6U2), pads 1-50 of 291")
	)
	(layers
		(0 "F.Cu" signal "TOP")
		(4 "In1.Cu" signal "L2GND")
		(6 "In2.Cu" signal "L3")
		(8 "In3.Cu" signal "L4GND")
		(10 "In4.Cu" signal "L5")
		(12 "In5.Cu" signal "L6GND")
		(14 "In6.Cu" signal "L7VCC")
		(16 "In7.Cu" signal "L8VCC")
		(18 "In8.Cu" signal "L9GND")
		(20 "In9.Cu" signal "L10")
		(22 "In10.Cu" signal "L11GND")
		(24 "In11.Cu" signal "L12")
		(26 "In12.Cu" signal "L13GND")
		(2 "B.Cu" signal "BOTTOM")
		(9 "F.Adhes" user "F.Adhesive")
		(11 "B.Adhes" user "B.Adhesive")
		(13 "F.Paste" user "Package Geometry/Pastemask Top")
		(15 "B.Paste" user "Package Geometry/Pastemask Bottom")
		(5 "F.SilkS" user "Ref Des/Silkscreen Top")
		(7 "B.SilkS" user "Ref Des/Silkscreen Bottom")
		(1 "F.Mask" user "Board Geometry/Soldermask Top")
		(3 "B.Mask" user "Board Geometry/Soldermask Bottom")
		(17 "Dwgs.User" user "User.Drawings")
		(19 "Cmts.User" user "User.Comments")
		(21 "Eco1.User" user "User.Eco1")
		(23 "Eco2.User" user "User.Eco2")
		(25 "Edge.Cuts" user "Board Geometry/Outline")
		(27 "Margin" user)
		(31 "F.CrtYd" user "Package Geometry/Place Bound Top")
		(29 "B.CrtYd" user "Package Geometry/Place Bound Bottom")
		(35 "F.Fab" user "Ref Des/Assembly Top")
		(33 "B.Fab" user "Ref Des/Assembly Bottom")
	)
	(footprint ""
		(layer "B.Cu")
		(at 194.700398 -5.621782 90)
		(property "Reference" "J6U2"
			(at 2.225548 39.48811 0)
			(unlocked yes)
			(layer "B.SilkS")
			(effects
				(font
					(size 0.7874 0.5842)
					(thickness 0.1524)
				)
				(justify left mirror)
			)
		)
		(property "Value" ""
			(at 0 0 90)
			(layer "B.Fab")
			(effects
				(font
					(size 1.27 1.27)
				)
				(justify mirror)
			)
		)
		(duplicate_pad_numbers_are_jumpers no)
		(pad "" thru_hole circle
			(at -2.29997 -5.649976 270)
			(size 2.8194 2.8194)
			(drill 2.4384)
			(layers "*.Cu" "*.Mask")
			(remove_unused_layers no)
			(clearance 0.127)
			(thermal_gap 0.127)
		)
		(pad "" thru_hole oval
			(at -2.29997 68.90004 270)
			(size 2.8194 1.5748)
			(drill oval 2.4384 1.1938)
			(layers "*.Cu" "*.Mask")
			(remove_unused_layers no)
			(clearance 0.127)
			(thermal_gap 0.127)
		)
		(pad "" thru_hole circle
			(at -2.29997 132.299964 270)
			(size 2.8194 2.8194)
			(drill 2.4384)
			(layers "*.Cu" "*.Mask")
			(remove_unused_layers no)
			(clearance 0.127)
			(thermal_gap 0.127)
		)
		(pad "1" smd rect
			(at 0 0 270)
			(size 1.8034 0.508)
			(layers "B.Cu" "B.Mask" "B.Paste")
			(net "P12V_NVDIMM_ABC")
		)
		(pad "2" smd rect
			(at 0 0.849884 270)
			(size 1.8034 0.508)
			(layers "B.Cu" "B.Mask" "B.Paste")
			(net "GND")
		)
		(pad "3" smd rect
			(at 0 1.700022 270)
			(size 1.8034 0.508)
			(layers "B.Cu" "B.Mask" "B.Paste")
			(net "M_C_DQ<4>")
		)
		(pad "4" smd rect
			(at 0 2.549906 270)
			(size 1.8034 0.508)
			(layers "B.Cu" "B.Mask" "B.Paste")
			(net "GND")
		)
		(pad "5" smd rect
			(at 0 3.400044 270)
			(size 1.8034 0.508)
			(layers "B.Cu" "B.Mask" "B.Paste")
			(net "M_C_DQ<0>")
		)
		(pad "6" smd rect
			(at 0 4.249928 270)
			(size 1.8034 0.508)
			(layers "B.Cu" "B.Mask" "B.Paste")
			(net "GND")
		)
		(pad "7" smd rect
			(at 0 5.100066 270)
			(size 1.8034 0.508)
			(layers "B.Cu" "B.Mask" "B.Paste")
			(net "M_C_DQS_DP<9>")
		)
		(pad "8" smd rect
			(at 0 5.94995 270)
			(size 1.8034 0.508)
			(layers "B.Cu" "B.Mask" "B.Paste")
			(net "M_C_DQS_DN<9>")
		)
		(pad "9" smd rect
			(at 0 6.800088 270)
			(size 1.8034 0.508)
			(layers "B.Cu" "B.Mask" "B.Paste")
			(net "GND")
		)
		(pad "10" smd rect
			(at 0 7.649972 270)
			(size 1.8034 0.508)
			(layers "B.Cu" "B.Mask" "B.Paste")
			(net "M_C_DQ<6>")
		)
		(pad "11" smd rect
			(at 0 8.50011 270)
			(size 1.8034 0.508)
			(layers "B.Cu" "B.Mask" "B.Paste")
			(net "GND")
		)
		(pad "12" smd rect
			(at 0 9.349994 270)
			(size 1.8034 0.508)
			(layers "B.Cu" "B.Mask" "B.Paste")
			(net "M_C_DQ<2>")
		)
		(pad "13" smd rect
			(at 0 10.199878 270)
			(size 1.8034 0.508)
			(layers "B.Cu" "B.Mask" "B.Paste")
			(net "GND")
		)
		(pad "14" smd rect
			(at 0 11.050016 270)
			(size 1.8034 0.508)
			(layers "B.Cu" "B.Mask" "B.Paste")
			(net "M_C_DQ<12>")
		)
		(pad "15" smd rect
			(at 0 11.8999 270)
			(size 1.8034 0.508)
			(layers "B.Cu" "B.Mask" "B.Paste")
			(net "GND")
		)
		(pad "16" smd rect
			(at 0 12.750038 270)
			(size 1.8034 0.508)
			(layers "B.Cu" "B.Mask" "B.Paste")
			(net "M_C_DQ<8>")
		)
		(pad "17" smd rect
			(at 0 13.599922 270)
			(size 1.8034 0.508)
			(layers "B.Cu" "B.Mask" "B.Paste")
			(net "GND")
		)
		(pad "18" smd rect
			(at 0 14.45006 270)
			(size 1.8034 0.508)
			(layers "B.Cu" "B.Mask" "B.Paste")
			(net "M_C_DQS_DP<10>")
		)
		(pad "19" smd rect
			(at 0 15.299944 270)
			(size 1.8034 0.508)
			(layers "B.Cu" "B.Mask" "B.Paste")
			(net "M_C_DQS_DN<10>")
		)
		(pad "20" smd rect
			(at 0 16.150082 270)
			(size 1.8034 0.508)
			(layers "B.Cu" "B.Mask" "B.Paste")
			(net "GND")
		)
		(pad "21" smd rect
			(at 0 16.999966 270)
			(size 1.8034 0.508)
			(layers "B.Cu" "B.Mask" "B.Paste")
			(net "M_C_DQ<14>")
		)
		(pad "22" smd rect
			(at 0 17.850104 270)
			(size 1.8034 0.508)
			(layers "B.Cu" "B.Mask" "B.Paste")
			(net "GND")
		)
		(pad "23" smd rect
			(at 0 18.699988 270)
			(size 1.8034 0.508)
			(layers "B.Cu" "B.Mask" "B.Paste")
			(net "M_C_DQ<10>")
		)
		(pad "24" smd rect
			(at 0 19.550126 270)
			(size 1.8034 0.508)
			(layers "B.Cu" "B.Mask" "B.Paste")
			(net "GND")
		)
		(pad "25" smd rect
			(at 0 20.40001 270)
			(size 1.8034 0.508)
			(layers "B.Cu" "B.Mask" "B.Paste")
			(net "M_C_DQ<20>")
		)
		(pad "26" smd rect
			(at 0 21.249894 270)
			(size 1.8034 0.508)
			(layers "B.Cu" "B.Mask" "B.Paste")
			(net "GND")
		)
		(pad "27" smd rect
			(at 0 22.100032 270)
			(size 1.8034 0.508)
			(layers "B.Cu" "B.Mask" "B.Paste")
			(net "M_C_DQ<16>")
		)
		(pad "28" smd rect
			(at 0 22.949916 270)
			(size 1.8034 0.508)
			(layers "B.Cu" "B.Mask" "B.Paste")
			(net "GND")
		)
		(pad "29" smd rect
			(at 0 23.800054 270)
			(size 1.8034 0.508)
			(layers "B.Cu" "B.Mask" "B.Paste")
			(net "M_C_DQS_DP<11>")
		)
		(pad "30" smd rect
			(at 0 24.649938 270)
			(size 1.8034 0.508)
			(layers "B.Cu" "B.Mask" "B.Paste")
			(net "M_C_DQS_DN<11>")
		)
		(pad "31" smd rect
			(at 0 25.500076 270)
			(size 1.8034 0.508)
			(layers "B.Cu" "B.Mask" "B.Paste")
			(net "GND")
		)
		(pad "32" smd rect
			(at 0 26.34996 270)
			(size 1.8034 0.508)
			(layers "B.Cu" "B.Mask" "B.Paste")
			(net "M_C_DQ<22>")
		)
		(pad "33" smd rect
			(at 0 27.200098 270)
			(size 1.8034 0.508)
			(layers "B.Cu" "B.Mask" "B.Paste")
			(net "GND")
		)
		(pad "34" smd rect
			(at 0 28.049982 270)
			(size 1.8034 0.508)
			(layers "B.Cu" "B.Mask" "B.Paste")
			(net "M_C_DQ<18>")
		)
		(pad "35" smd rect
			(at 0 28.90012 270)
			(size 1.8034 0.508)
			(layers "B.Cu" "B.Mask" "B.Paste")
			(net "GND")
		)
		(pad "36" smd rect
			(at 0 29.750004 270)
			(size 1.8034 0.508)
			(layers "B.Cu" "B.Mask" "B.Paste")
			(net "M_C_DQ<28>")
		)
		(pad "37" smd rect
			(at 0 30.599888 270)
			(size 1.8034 0.508)
			(layers "B.Cu" "B.Mask" "B.Paste")
			(net "GND")
		)
		(pad "38" smd rect
			(at 0 31.450026 270)
			(size 1.8034 0.508)
			(layers "B.Cu" "B.Mask" "B.Paste")
			(net "M_C_DQ<24>")
		)
		(pad "39" smd rect
			(at 0 32.29991 270)
			(size 1.8034 0.508)
			(layers "B.Cu" "B.Mask" "B.Paste")
			(net "GND")
		)
		(pad "40" smd rect
			(at 0 33.150048 270)
			(size 1.8034 0.508)
			(layers "B.Cu" "B.Mask" "B.Paste")
			(net "M_C_DQS_DP<12>")
		)
		(pad "41" smd rect
			(at 0 33.999932 270)
			(size 1.8034 0.508)
			(layers "B.Cu" "B.Mask" "B.Paste")
			(net "M_C_DQS_DN<12>")
		)
		(pad "42" smd rect
			(at 0 34.85007 270)
			(size 1.8034 0.508)
			(layers "B.Cu" "B.Mask" "B.Paste")
			(net "GND")
		)
		(pad "43" smd rect
			(at 0 35.699954 270)
			(size 1.8034 0.508)
			(layers "B.Cu" "B.Mask" "B.Paste")
			(net "M_C_DQ<30>")
		)
		(pad "44" smd rect
			(at 0 36.550092 270)
			(size 1.8034 0.508)
			(layers "B.Cu" "B.Mask" "B.Paste")
			(net "GND")
		)
		(pad "45" smd rect
			(at 0 37.399976 270)
			(size 1.8034 0.508)
			(layers "B.Cu" "B.Mask" "B.Paste")
			(net "M_C_DQ<26>")
		)
		(pad "46" smd rect
			(at 0 38.250114 270)
			(size 1.8034 0.508)
			(layers "B.Cu" "B.Mask" "B.Paste")
			(net "GND")
		)
		(pad "47" smd rect
			(at 0 39.099998 270)
			(size 1.8034 0.508)
			(layers "B.Cu" "B.Mask" "B.Paste")
			(net "M_C_ECC<4>")
		)
	)
)
